# BASEBOARD_FAB2 (Tioga Pass) — schematic netlist excerpt (pin names and nets, part order shuffled) for the footprints in the layout excerpt that follows; sources: Cadence DE-HDL packaged netlist, KiCad conversion of Wiwynn_Tioga_Pass_MB.brd

C8G4  CAP  0.22UF 16V 10% X7R  pkg 0402  page 105 : A = P3E_CPU0_PE2_SS_TXN<3> ; B = P3E_CPU0_PE2_SS_C_TXN<3>
R8C18  RES  1.00K 1% CHIP  pkg 0402  page 125 : A = P3V3_STBY ; B = PU_PCH_TLS_ENABLE_STRAP
R9G35  RES  2.7K 1% CHIP  pkg 0402  page 169 : A = P3V3_STBY ; B = FM_BATTERY_SENSE_EN_N

(kicad_pcb
	(version 20260206)
	(generator "pcbnew")
	(generator_version "10.0")
	(general
		(thickness 1.6)
		(legacy_teardrops no)
	)
	(paper "A4")
	(title_block
		(title "Wiwynn_Tioga_Pass_MB.brd")
		(comment 1 "Tioga Pass / footprints 420-422 of 4770")
	)
	(layers
		(0 "F.Cu" signal "TOP")
		(4 "In1.Cu" signal "L2GND")
		(6 "In2.Cu" signal "L3")
		(8 "In3.Cu" signal "L4GND")
		(10 "In4.Cu" signal "L5")
		(12 "In5.Cu" signal "L6GND")
		(14 "In6.Cu" signal "L7VCC")
		(16 "In7.Cu" signal "L8VCC")
		(18 "In8.Cu" signal "L9GND")
		(20 "In9.Cu" signal "L10")
		(22 "In10.Cu" signal "L11GND")
		(24 "In11.Cu" signal "L12")
		(26 "In12.Cu" signal "L13GND")
		(2 "B.Cu" signal "BOTTOM")
		(9 "F.Adhes" user "F.Adhesive")
		(11 "B.Adhes" user "B.Adhesive")
		(13 "F.Paste" user "Package Geometry/Pastemask Top")
		(15 "B.Paste" user "Package Geometry/Pastemask Bottom")
		(5 "F.SilkS" user "Ref Des/Silkscreen Top")
		(7 "B.SilkS" user "Ref Des/Silkscreen Bottom")
		(1 "F.Mask" user "Board Geometry/Soldermask Top")
		(3 "B.Mask" user "Board Geometry/Soldermask Bottom")
		(17 "Dwgs.User" user "User.Drawings")
		(19 "Cmts.User" user "User.Comments")
		(21 "Eco1.User" user "User.Eco1")
		(23 "Eco2.User" user "User.Eco2")
		(25 "Edge.Cuts" user "Board Geometry/Outline")
		(27 "Margin" user)
		(31 "F.CrtYd" user "Package Geometry/Place Bound Top")
		(29 "B.CrtYd" user "Package Geometry/Place Bound Bottom")
		(35 "F.Fab" user "Ref Des/Assembly Top")
		(33 "B.Fab" user "Ref Des/Assembly Bottom")
	)
	(footprint ""
		(layer "F.Cu")
		(at 465.7344 3.9878 90)
		(property "Reference" "R9G35"
			(at 0 0 90)
			(layer "F.SilkS")
			(hide yes)
			(effects
				(font
					(size 1.27 1.27)
				)
			)
		)
		(property "Value" ""
			(at 0 0 90)
			(layer "F.Fab")
			(effects
				(font
					(size 1.27 1.27)
				)
			)
		)
		(duplicate_pad_numbers_are_jumpers no)
		(fp_poly
			(pts
				(xy -0.2794 -0.1016) (xy 0.2794 -0.1016) (xy 0.2794 0.9906) (xy -0.2794 0.9906)
			)
			(stroke
				(width 0)
				(type default)
			)
			(fill no)
			(layer "F.CrtYd")
		)
		(fp_line
			(start 0.2794 -0.1016)
			(end -0.2794 -0.1016)
			(stroke
				(width 0.1)
				(type default)
			)
			(layer "F.Fab")
		)
		(fp_line
			(start -0.2794 -0.1016)
			(end -0.2794 0.9906)
			(stroke
				(width 0.1)
				(type default)
			)
			(layer "F.Fab")
		)
		(fp_line
			(start 0.2794 0.9906)
			(end 0.2794 -0.1016)
			(stroke
				(width 0.1)
				(type default)
			)
			(layer "F.Fab")
		)
		(fp_line
			(start -0.2794 0.9906)
			(end 0.2794 0.9906)
			(stroke
				(width 0.1)
				(type default)
			)
			(layer "F.Fab")
		)
		(pad "1" smd rect
			(at 0 0 90)
			(size 0.508 0.508)
			(layers "F.Cu" "F.Mask" "F.Paste")
			(net "P3V3_STBY")
		)
		(pad "2" smd rect
			(at 0 0.889 90)
			(size 0.508 0.508)
			(layers "F.Cu" "F.Mask" "F.Paste")
			(net "FM_BATTERY_SENSE_EN_N")
		)
		(zone
			(layer "F.Cu")
			(hatch none 0.5)
			(connect_pads
				(clearance 0)
			)
			(min_thickness 0.25)
			(keepout
				(tracks allowed)
				(vias not_allowed)
				(pads allowed)
				(copperpour not_allowed)
				(footprints allowed)
			)
			(placement
				(enabled no)
				(sheetname "")
			)
			(fill
				(thermal_gap 0.5)
				(thermal_bridge_width 0.5)
				(island_removal_mode 0)
			)
			(polygon
				(pts
					(xy 465.9884 4.2418) (xy 465.9884 3.7338) (xy 466.3694 3.7338) (xy 466.3694 4.2418)
				)
			)
		)
		(zone
			(layer "F.Cu")
			(hatch none 0.5)
			(connect_pads
				(clearance 0)
			)
			(min_thickness 0.25)
			(keepout
				(tracks not_allowed)
				(vias allowed)
				(pads allowed)
				(copperpour not_allowed)
				(footprints allowed)
			)
			(placement
				(enabled no)
				(sheetname "")
			)
			(fill
				(thermal_gap 0.5)
				(thermal_bridge_width 0.5)
				(island_removal_mode 0)
			)
			(polygon
				(pts
					(xy 466.3694 4.2418) (xy 466.3694 3.7338) (xy 465.9884 3.7338) (xy 465.9884 4.2418)
				)
			)
		)
	)
	(footprint ""
		(layer "F.Cu")
		(at 403.719792 -10.917936)
		(property "Reference" "C8G4"
			(at 0 0 0)
			(layer "F.SilkS")
			(hide yes)
			(effects
				(font
					(size 1.27 1.27)
				)
			)
		)
		(property "Value" ""
			(at 0 0 0)
			(layer "F.Fab")
			(effects
				(font
					(size 1.27 1.27)
				)
			)
		)
		(duplicate_pad_numbers_are_jumpers no)
		(fp_rect
			(start -0.3048 0.9906)
			(end 0.3048 -0.1016)
			(stroke
				(width 0)
				(type default)
			)
			(fill no)
			(layer "F.CrtYd")
		)
		(fp_line
			(start -0.3048 -0.1016)
			(end -0.3048 0.9906)
			(stroke
				(width 0.1)
				(type default)
			)
			(layer "F.Fab")
		)
		(fp_line
			(start -0.3048 0.9906)
			(end 0.3048 0.9906)
			(stroke
				(width 0.1)
				(type default)
			)
			(layer "F.Fab")
		)
		(fp_line
			(start 0.3048 -0.1016)
			(end -0.3048 -0.1016)
			(stroke
				(width 0.1)
				(type default)
			)
			(layer "F.Fab")
		)
		(fp_line
			(start 0.3048 0.9906)
			(end 0.3048 -0.1016)
			(stroke
				(width 0.1)
				(type default)
			)
			(layer "F.Fab")
		)
		(pad "1" smd rect
			(at 0 0)
			(size 0.508 0.508)
			(layers "F.Cu" "F.Mask" "F.Paste")
			(net "P3E_CPU0_PE2_SS_TXN<3>")
		)
		(pad "2" smd rect
			(at 0 0.889)
			(size 0.508 0.508)
			(layers "F.Cu" "F.Mask" "F.Paste")
			(net "P3E_CPU0_PE2_SS_C_TXN<3>")
		)
		(zone
			(layer "F.Cu")
			(hatch none 0.5)
			(connect_pads
				(clearance 0)
			)
			(min_thickness 0.25)
			(keepout
				(tracks allowed)
				(vias not_allowed)
				(pads allowed)
				(copperpour not_allowed)
				(footprints allowed)
			)
			(placement
				(enabled no)
				(sheetname "")
			)
			(fill
				(thermal_gap 0.5)
				(thermal_bridge_width 0.5)
				(island_removal_mode 0)
			)
			(polygon
				(pts
					(xy 403.465792 -10.282936) (xy 403.973792 -10.282936) (xy 403.973792 -10.663936) (xy 403.465792 -10.663936)
				)
			)
		)
		(zone
			(layer "F.Cu")
			(hatch none 0.5)
			(connect_pads
				(clearance 0)
			)
			(min_thickness 0.25)
			(keepout
				(tracks not_allowed)
				(vias allowed)
				(pads allowed)
				(copperpour not_allowed)
				(footprints allowed)
			)
			(placement
				(enabled no)
				(sheetname "")
			)
			(fill
				(thermal_gap 0.5)
				(thermal_bridge_width 0.5)
				(island_removal_mode 0)
			)
			(polygon
				(pts
					(xy 403.465792 -10.282936) (xy 403.973792 -10.282936) (xy 403.973792 -10.663936) (xy 403.465792 -10.663936)
				)
			)
		)
	)
	(footprint ""
		(layer "F.Cu")
		(at 411.1625 -105.537 -90)
		(property "Reference" "R8C18"
			(at 0 0 270)
			(layer "F.SilkS")
			(hide yes)
			(effects
				(font
					(size 1.27 1.27)
				)
			)
		)
		(property "Value" ""
			(at 0 0 270)
			(layer "F.Fab")
			(effects
				(font
					(size 1.27 1.27)
				)
			)
		)
		(duplicate_pad_numbers_are_jumpers no)
		(fp_poly
			(pts
				(xy -0.2794 -0.1016) (xy 0.2794 -0.1016) (xy 0.2794 0.9906) (xy -0.2794 0.9906)
			)
			(stroke
				(width 0)
				(type default)
			)
			(fill no)
			(layer "F.CrtYd")
		)
		(fp_line
			(start -0.2794 0.9906)
			(end 0.2794 0.9906)
			(stroke
				(width 0.1)
				(type default)
			)
			(layer "F.Fab")
		)
		(fp_line
			(start 0.2794 0.9906)
			(end 0.2794 -0.1016)
			(stroke
				(width 0.1)
				(type default)
			)
			(layer "F.Fab")
		)
		(fp_line
			(start -0.2794 -0.1016)
			(end -0.2794 0.9906)
			(stroke
				(width 0.1)
				(type default)
			)
			(layer "F.Fab")
		)
		(fp_line
			(start 0.2794 -0.1016)
			(end -0.2794 -0.1016)
			(stroke
				(width 0.1)
				(type default)
			)
			(layer "F.Fab")
		)
		(pad "1" smd rect
			(at 0 0 270)
			(size 0.508 0.508)
			(layers "F.Cu" "F.Mask" "F.Paste")
			(net "P3V3_STBY")
		)
		(pad "2" smd rect
			(at 0 0.889 270)
			(size 0.508 0.508)
			(layers "F.Cu" "F.Mask" "F.Paste")
			(net "PU_PCH_TLS_ENABLE_STRAP")
		)
		(zone
			(layer "F.Cu")
			(hatch none 0.5)
			(connect_pads
				(clearance 0)
			)
			(min_thickness 0.25)
			(keepout
				(tracks not_allowed)
				(vias allowed)
				(pads allowed)
				(copperpour not_allowed)
				(footprints allowed)
			)
			(placement
				(enabled no)
				(sheetname "")
			)
			(fill
				(thermal_gap 0.5)
				(thermal_bridge_width 0.5)
				(island_removal_mode 0)
			)
			(polygon
				(pts
					(xy 410.5275 -105.791) (xy 410.5275 -105.283) (xy 410.9085 -105.283) (xy 410.9085 -105.791)
				)
			)
		)
		(zone
			(layer "F.Cu")
			(hatch none 0.5)
			(connect_pads
				(clearance 0)
			)
			(min_thickness 0.25)
			(keepout
				(tracks allowed)
				(vias not_allowed)
				(pads allowed)
				(copperpour not_allowed)
				(footprints allowed)
			)
			(placement
				(enabled no)
				(sheetname "")
			)
			(fill
				(thermal_gap 0.5)
				(thermal_bridge_width 0.5)
				(island_removal_mode 0)
			)
			(polygon
				(pts
					(xy 410.9085 -105.791) (xy 410.9085 -105.283) (xy 410.5275 -105.283) (xy 410.5275 -105.791)
				)
			)
		)
	)
)
